# T6G (Grand Teton) — schematic netlist excerpt (pin names and nets, part order shuffled) for the footprints in the layout excerpt that follows; sources: Cadence DE-HDL packaged netlist, KiCad conversion of 04192023_DAF0TMB3IC0_F0TG_MB_C_brd_V02_OCP.brd

R8097  Q_RES  0 5% CHIP  pkg 0402LF  page 142 : A = OCP_V3_2_P3V3_R1_PWRGD ; B = OCP_V3_2_P3V3_PWRGD
R1508  Q_RES  100 1% CHIP  pkg 0402LF  page 167 : A = GND ; B = PD_BIOS_DEBUG_MODE

(kicad_pcb
	(version 20260206)
	(generator "pcbnew")
	(generator_version "10.0")
	(general
		(thickness 1.6)
		(legacy_teardrops no)
	)
	(paper "A4")
	(title_block
		(title "04192023_DAF0TMB3IC0_F0TG_MB_C_brd_V02_OCP.brd")
		(comment 1 "Grand Teton / footprints 1561-1562 of 8354")
	)
	(layers
		(0 "F.Cu" signal "TOP")
		(4 "In1.Cu" signal "GND")
		(6 "In2.Cu" signal "IN1")
		(8 "In3.Cu" signal "GND1")
		(10 "In4.Cu" signal "IN2")
		(12 "In5.Cu" signal "GND2")
		(14 "In6.Cu" signal "IN3")
		(16 "In7.Cu" signal "GND3")
		(18 "In8.Cu" signal "VCC")
		(20 "In9.Cu" signal "VCC1")
		(22 "In10.Cu" signal "GND4")
		(24 "In11.Cu" signal "IN4")
		(26 "In12.Cu" signal "GND5")
		(28 "In13.Cu" signal "IN5")
		(30 "In14.Cu" signal "GND6")
		(32 "In15.Cu" signal "IN6")
		(34 "In16.Cu" signal "GND7")
		(2 "B.Cu" signal "BOTTOM")
		(9 "F.Adhes" user "F.Adhesive")
		(11 "B.Adhes" user "B.Adhesive")
		(13 "F.Paste" user "Package Geometry/Pastemask Top")
		(15 "B.Paste" user "Package Geometry/Pastemask Bottom")
		(5 "F.SilkS" user "Ref Des/Silkscreen Top")
		(7 "B.SilkS" user "Ref Des/Silkscreen Bottom")
		(1 "F.Mask" user "Board Geometry/Soldermask Top")
		(3 "B.Mask" user "Board Geometry/Soldermask Bottom")
		(17 "Dwgs.User" user "User.Drawings")
		(19 "Cmts.User" user "User.Comments")
		(21 "Eco1.User" user "User.Eco1")
		(23 "Eco2.User" user "User.Eco2")
		(25 "Edge.Cuts" user "Board Geometry/Outline")
		(27 "Margin" user)
		(31 "F.CrtYd" user "Package Geometry/Place Bound Top")
		(29 "B.CrtYd" user "Package Geometry/Place Bound Bottom")
		(35 "F.Fab" user "Ref Des/Assembly Top")
		(33 "B.Fab" user "Ref Des/Assembly Bottom")
	)
	(footprint ""
		(layer "F.Cu")
		(at 80.645 -66.802)
		(property "Reference" "R8097"
			(at 0 0 0)
			(layer "F.SilkS")
			(hide yes)
			(effects
				(font
					(size 1.27 1.27)
				)
			)
		)
		(property "Value" ""
			(at 0 0 0)
			(layer "F.Fab")
			(effects
				(font
					(size 1.27 1.27)
				)
			)
		)
		(duplicate_pad_numbers_are_jumpers no)
		(fp_line
			(start -0.7874 -0.4064)
			(end 0.7874 -0.4064)
			(stroke
				(width 0.1524)
				(type default)
			)
			(layer "F.SilkS")
		)
		(fp_line
			(start -0.7874 0.4064)
			(end -0.7874 -0.4064)
			(stroke
				(width 0.1524)
				(type default)
			)
			(layer "F.SilkS")
		)
		(fp_line
			(start 0.7874 -0.4064)
			(end 0.7874 0.4064)
			(stroke
				(width 0.1524)
				(type default)
			)
			(layer "F.SilkS")
		)
		(fp_line
			(start 0.7874 0.4064)
			(end -0.7874 0.4064)
			(stroke
				(width 0.1524)
				(type default)
			)
			(layer "F.SilkS")
		)
		(fp_line
			(start -0.67945 -0.305054)
			(end -0.12065 -0.305054)
			(stroke
				(width 0.1)
				(type default)
			)
			(layer "F.Fab")
		)
		(fp_line
			(start -0.67945 0.3048)
			(end -0.67945 -0.305054)
			(stroke
				(width 0.1)
				(type default)
			)
			(layer "F.Fab")
		)
		(fp_line
			(start -0.12065 -0.305054)
			(end -0.12065 -0.2794)
			(stroke
				(width 0.1)
				(type default)
			)
			(layer "F.Fab")
		)
		(fp_line
			(start -0.12065 -0.2794)
			(end 0.12065 -0.2794)
			(stroke
				(width 0.1)
				(type default)
			)
			(layer "F.Fab")
		)
		(fp_line
			(start -0.12065 0.2794)
			(end -0.12065 0.3048)
			(stroke
				(width 0.1)
				(type default)
			)
			(layer "F.Fab")
		)
		(fp_line
			(start -0.12065 0.3048)
			(end -0.67945 0.3048)
			(stroke
				(width 0.1)
				(type default)
			)
			(layer "F.Fab")
		)
		(fp_line
			(start 0.120396 0.2794)
			(end -0.12065 0.2794)
			(stroke
				(width 0.1)
				(type default)
			)
			(layer "F.Fab")
		)
		(fp_line
			(start 0.120396 0.3048)
			(end 0.120396 0.2794)
			(stroke
				(width 0.1)
				(type default)
			)
			(layer "F.Fab")
		)
		(fp_line
			(start 0.12065 -0.3048)
			(end 0.67945 -0.3048)
			(stroke
				(width 0.1)
				(type default)
			)
			(layer "F.Fab")
		)
		(fp_line
			(start 0.12065 -0.2794)
			(end 0.12065 -0.3048)
			(stroke
				(width 0.1)
				(type default)
			)
			(layer "F.Fab")
		)
		(fp_line
			(start 0.67945 -0.3048)
			(end 0.67945 0.3048)
			(stroke
				(width 0.1)
				(type default)
			)
			(layer "F.Fab")
		)
		(fp_line
			(start 0.67945 0.3048)
			(end 0.120396 0.3048)
			(stroke
				(width 0.1)
				(type default)
			)
			(layer "F.Fab")
		)
		(pad "1" smd circle
			(at -0.40005 0)
			(size 0 0)
			(layers "F.Cu" "F.Mask" "F.Paste")
			(net "OCP_V3_2_P3V3_R1_PWRGD")
		)
		(pad "2" smd circle
			(at 0.40005 0)
			(size 0 0)
			(layers "F.Cu" "F.Mask" "F.Paste")
			(net "OCP_V3_2_P3V3_PWRGD")
		)
	)
	(footprint ""
		(layer "F.Cu")
		(at 420.75735 -36.007548)
		(property "Reference" "R1508"
			(at 0 0 0)
			(layer "F.SilkS")
			(hide yes)
			(effects
				(font
					(size 1.27 1.27)
				)
			)
		)
		(property "Value" ""
			(at 0 0 0)
			(layer "F.Fab")
			(effects
				(font
					(size 1.27 1.27)
				)
			)
		)
		(duplicate_pad_numbers_are_jumpers no)
		(fp_line
			(start -0.7874 -0.406146)
			(end 0.7874 -0.406146)
			(stroke
				(width 0.1524)
				(type default)
			)
			(layer "F.SilkS")
		)
		(fp_line
			(start -0.7874 0.406146)
			(end -0.7874 -0.406146)
			(stroke
				(width 0.1524)
				(type default)
			)
			(layer "F.SilkS")
		)
		(fp_line
			(start 0.7874 -0.406146)
			(end 0.7874 0.406146)
			(stroke
				(width 0.1524)
				(type default)
			)
			(layer "F.SilkS")
		)
		(fp_line
			(start 0.7874 0.406146)
			(end -0.7874 0.406146)
			(stroke
				(width 0.1524)
				(type default)
			)
			(layer "F.SilkS")
		)
		(fp_line
			(start -0.67945 -0.305054)
			(end -0.12065 -0.305054)
			(stroke
				(width 0.1)
				(type default)
			)
			(layer "F.Fab")
		)
		(fp_line
			(start -0.67945 0.3048)
			(end -0.67945 -0.305054)
			(stroke
				(width 0.1)
				(type default)
			)
			(layer "F.Fab")
		)
		(fp_line
			(start -0.12065 -0.305054)
			(end -0.12065 -0.2794)
			(stroke
				(width 0.1)
				(type default)
			)
			(layer "F.Fab")
		)
		(fp_line
			(start -0.12065 -0.2794)
			(end 0.12065 -0.2794)
			(stroke
				(width 0.1)
				(type default)
			)
			(layer "F.Fab")
		)
		(fp_line
			(start -0.12065 0.2794)
			(end -0.120396 0.3048)
			(stroke
				(width 0.1)
				(type default)
			)
			(layer "F.Fab")
		)
		(fp_line
			(start -0.120396 0.3048)
			(end -0.67945 0.3048)
			(stroke
				(width 0.1)
				(type default)
			)
			(layer "F.Fab")
		)
		(fp_line
			(start 0.120396 -0.3048)
			(end 0.67945 -0.3048)
			(stroke
				(width 0.1)
				(type default)
			)
			(layer "F.Fab")
		)
		(fp_line
			(start 0.120396 0.2794)
			(end -0.12065 0.2794)
			(stroke
				(width 0.1)
				(type default)
			)
			(layer "F.Fab")
		)
		(fp_line
			(start 0.120396 0.3048)
			(end 0.120396 0.2794)
			(stroke
				(width 0.1)
				(type default)
			)
			(layer "F.Fab")
		)
		(fp_line
			(start 0.12065 -0.2794)
			(end 0.120396 -0.3048)
			(stroke
				(width 0.1)
				(type default)
			)
			(layer "F.Fab")
		)
		(fp_line
			(start 0.67945 -0.3048)
			(end 0.67945 0.3048)
			(stroke
				(width 0.1)
				(type default)
			)
			(layer "F.Fab")
		)
		(fp_line
			(start 0.67945 0.3048)
			(end 0.120396 0.3048)
			(stroke
				(width 0.1)
				(type default)
			)
			(layer "F.Fab")
		)
		(pad "1" smd circle
			(at -0.40005 0)
			(size 0 0)
			(layers "F.Cu" "F.Mask" "F.Paste")
			(net "GND")
		)
		(pad "2" smd circle
			(at 0.40005 0)
			(size 0 0)
			(layers "F.Cu" "F.Mask" "F.Paste")
			(net "PD_BIOS_DEBUG_MODE")
		)
	)
)
